# T6G (Grand Teton) — schematic netlist excerpt (pin names and nets, part order shuffled) for the footprints in the layout excerpt that follows; sources: Cadence DE-HDL packaged netlist, KiCad conversion of 04192023_DAF0TMB3IC0_F0TG_MB_C_brd_V02_OCP.brd

R356  Q_RES  0 5% CHIP  pkg 0402LF  page 27 : A = CPU0_XTRIG_R2_L6 ; B = CPU0_XTRIG_L6
R1418  Q_RES  1K 1% CHIP  pkg 0201LF  page 185 : A = P1V8_CPU0_RT_1D ; B = SMB_RT_CPU0_P1_ROM_MUX_1D_SCL
R6259  Q_RES  0 5% CHIP  pkg 0402LF  page 178 : A = P1V2_CPU0_USB2_DVDD12 ; B = USB_HUB2_TI_PWRCTL2_MRP_VDD12

(kicad_pcb
	(version 20260206)
	(generator "pcbnew")
	(generator_version "10.0")
	(general
		(thickness 1.6)
		(legacy_teardrops no)
	)
	(paper "A4")
	(title_block
		(title "04192023_DAF0TMB3IC0_F0TG_MB_C_brd_V02_OCP.brd")
		(comment 1 "Grand Teton / footprints 4679-4681 of 8354")
	)
	(layers
		(0 "F.Cu" signal "TOP")
		(4 "In1.Cu" signal "GND")
		(6 "In2.Cu" signal "IN1")
		(8 "In3.Cu" signal "GND1")
		(10 "In4.Cu" signal "IN2")
		(12 "In5.Cu" signal "GND2")
		(14 "In6.Cu" signal "IN3")
		(16 "In7.Cu" signal "GND3")
		(18 "In8.Cu" signal "VCC")
		(20 "In9.Cu" signal "VCC1")
		(22 "In10.Cu" signal "GND4")
		(24 "In11.Cu" signal "IN4")
		(26 "In12.Cu" signal "GND5")
		(28 "In13.Cu" signal "IN5")
		(30 "In14.Cu" signal "GND6")
		(32 "In15.Cu" signal "IN6")
		(34 "In16.Cu" signal "GND7")
		(2 "B.Cu" signal "BOTTOM")
		(9 "F.Adhes" user "F.Adhesive")
		(11 "B.Adhes" user "B.Adhesive")
		(13 "F.Paste" user "Package Geometry/Pastemask Top")
		(15 "B.Paste" user "Package Geometry/Pastemask Bottom")
		(5 "F.SilkS" user "Ref Des/Silkscreen Top")
		(7 "B.SilkS" user "Ref Des/Silkscreen Bottom")
		(1 "F.Mask" user "Board Geometry/Soldermask Top")
		(3 "B.Mask" user "Board Geometry/Soldermask Bottom")
		(17 "Dwgs.User" user "User.Drawings")
		(19 "Cmts.User" user "User.Comments")
		(21 "Eco1.User" user "User.Eco1")
		(23 "Eco2.User" user "User.Eco2")
		(25 "Edge.Cuts" user "Board Geometry/Outline")
		(27 "Margin" user)
		(31 "F.CrtYd" user "Package Geometry/Place Bound Top")
		(29 "B.CrtYd" user "Package Geometry/Place Bound Bottom")
		(35 "F.Fab" user "Ref Des/Assembly Top")
		(33 "B.Fab" user "Ref Des/Assembly Bottom")
	)
	(footprint ""
		(layer "F.Cu")
		(at 122.427238 -41.17975 -90)
		(property "Reference" "R6259"
			(at 0 0 270)
			(layer "F.SilkS")
			(hide yes)
			(effects
				(font
					(size 1.27 1.27)
				)
			)
		)
		(property "Value" ""
			(at 0 0 270)
			(layer "F.Fab")
			(effects
				(font
					(size 1.27 1.27)
				)
			)
		)
		(duplicate_pad_numbers_are_jumpers no)
		(fp_line
			(start -0.7874 0.4064)
			(end -0.7874 -0.4064)
			(stroke
				(width 0.1524)
				(type default)
			)
			(layer "F.SilkS")
		)
		(fp_line
			(start 0.7874 0.4064)
			(end -0.7874 0.4064)
			(stroke
				(width 0.1524)
				(type default)
			)
			(layer "F.SilkS")
		)
		(fp_line
			(start -0.7874 -0.4064)
			(end 0.7874 -0.4064)
			(stroke
				(width 0.1524)
				(type default)
			)
			(layer "F.SilkS")
		)
		(fp_line
			(start 0.7874 -0.4064)
			(end 0.7874 0.4064)
			(stroke
				(width 0.1524)
				(type default)
			)
			(layer "F.SilkS")
		)
		(fp_line
			(start -0.67945 0.3048)
			(end -0.67945 -0.305054)
			(stroke
				(width 0.1)
				(type default)
			)
			(layer "F.Fab")
		)
		(fp_line
			(start -0.12065 0.3048)
			(end -0.67945 0.3048)
			(stroke
				(width 0.1)
				(type default)
			)
			(layer "F.Fab")
		)
		(fp_line
			(start 0.120396 0.3048)
			(end 0.120396 0.2794)
			(stroke
				(width 0.1)
				(type default)
			)
			(layer "F.Fab")
		)
		(fp_line
			(start 0.67945 0.3048)
			(end 0.120396 0.3048)
			(stroke
				(width 0.1)
				(type default)
			)
			(layer "F.Fab")
		)
		(fp_line
			(start -0.12065 0.2794)
			(end -0.12065 0.3048)
			(stroke
				(width 0.1)
				(type default)
			)
			(layer "F.Fab")
		)
		(fp_line
			(start 0.120396 0.2794)
			(end -0.12065 0.2794)
			(stroke
				(width 0.1)
				(type default)
			)
			(layer "F.Fab")
		)
		(fp_line
			(start -0.12065 -0.2794)
			(end 0.12065 -0.2794)
			(stroke
				(width 0.1)
				(type default)
			)
			(layer "F.Fab")
		)
		(fp_line
			(start 0.12065 -0.2794)
			(end 0.12065 -0.3048)
			(stroke
				(width 0.1)
				(type default)
			)
			(layer "F.Fab")
		)
		(fp_line
			(start 0.12065 -0.3048)
			(end 0.67945 -0.3048)
			(stroke
				(width 0.1)
				(type default)
			)
			(layer "F.Fab")
		)
		(fp_line
			(start 0.67945 -0.3048)
			(end 0.67945 0.3048)
			(stroke
				(width 0.1)
				(type default)
			)
			(layer "F.Fab")
		)
		(fp_line
			(start -0.67945 -0.305054)
			(end -0.12065 -0.305054)
			(stroke
				(width 0.1)
				(type default)
			)
			(layer "F.Fab")
		)
		(fp_line
			(start -0.12065 -0.305054)
			(end -0.12065 -0.2794)
			(stroke
				(width 0.1)
				(type default)
			)
			(layer "F.Fab")
		)
		(pad "1" smd circle
			(at -0.40005 0 270)
			(size 0 0)
			(layers "F.Cu" "F.Mask" "F.Paste")
			(net "P1V2_CPU0_USB2_DVDD12")
		)
		(pad "2" smd circle
			(at 0.40005 0 270)
			(size 0 0)
			(layers "F.Cu" "F.Mask" "F.Paste")
			(net "USB_HUB2_TI_PWRCTL2_MRP_VDD12")
		)
	)
	(footprint ""
		(layer "F.Cu")
		(at 294.759888 -392.32205 180)
		(property "Reference" "R1418"
			(at 0 0 180)
			(layer "F.SilkS")
			(hide yes)
			(effects
				(font
					(size 1.27 1.27)
				)
			)
		)
		(property "Value" ""
			(at 0 0 180)
			(layer "F.Fab")
			(effects
				(font
					(size 1.27 1.27)
				)
			)
		)
		(duplicate_pad_numbers_are_jumpers no)
		(fp_line
			(start 0.32512 0.175006)
			(end -0.32512 0.175006)
			(stroke
				(width 0.1)
				(type default)
			)
			(layer "F.Fab")
		)
		(fp_line
			(start 0.32512 -0.175006)
			(end 0.32512 0.175006)
			(stroke
				(width 0.1)
				(type default)
			)
			(layer "F.Fab")
		)
		(fp_line
			(start -0.32512 0.175006)
			(end -0.32512 -0.175006)
			(stroke
				(width 0.1)
				(type default)
			)
			(layer "F.Fab")
		)
		(fp_line
			(start -0.32512 -0.175006)
			(end 0.32512 -0.175006)
			(stroke
				(width 0.1)
				(type default)
			)
			(layer "F.Fab")
		)
		(pad "1" smd rect
			(at -0.2667 0 180)
			(size 0.3048 0.381)
			(layers "F.Cu" "F.Mask" "F.Paste")
			(net "P1V8_CPU0_RT_1D")
		)
		(pad "2" smd rect
			(at 0.2667 0)
			(size 0.3048 0.381)
			(layers "F.Cu" "F.Mask" "F.Paste")
			(net "SMB_RT_CPU0_P1_ROM_MUX_1D_SCL")
		)
	)
	(footprint ""
		(layer "F.Cu")
		(at 328.339958 -194.052952 -90)
		(property "Reference" "R356"
			(at 0 0 270)
			(layer "F.SilkS")
			(hide yes)
			(effects
				(font
					(size 1.27 1.27)
				)
			)
		)
		(property "Value" ""
			(at 0 0 270)
			(layer "F.Fab")
			(effects
				(font
					(size 1.27 1.27)
				)
			)
		)
		(duplicate_pad_numbers_are_jumpers no)
		(fp_line
			(start -0.7874 0.4064)
			(end -0.7874 -0.4064)
			(stroke
				(width 0.1524)
				(type default)
			)
			(layer "F.SilkS")
		)
		(fp_line
			(start 0.7874 0.4064)
			(end -0.7874 0.4064)
			(stroke
				(width 0.1524)
				(type default)
			)
			(layer "F.SilkS")
		)
		(fp_line
			(start -0.7874 -0.4064)
			(end 0.7874 -0.4064)
			(stroke
				(width 0.1524)
				(type default)
			)
			(layer "F.SilkS")
		)
		(fp_line
			(start 0.7874 -0.4064)
			(end 0.7874 0.4064)
			(stroke
				(width 0.1524)
				(type default)
			)
			(layer "F.SilkS")
		)
		(fp_line
			(start -0.67945 0.3048)
			(end -0.67945 -0.305054)
			(stroke
				(width 0.1)
				(type default)
			)
			(layer "F.Fab")
		)
		(fp_line
			(start -0.12065 0.3048)
			(end -0.67945 0.3048)
			(stroke
				(width 0.1)
				(type default)
			)
			(layer "F.Fab")
		)
		(fp_line
			(start 0.120396 0.3048)
			(end 0.120396 0.2794)
			(stroke
				(width 0.1)
				(type default)
			)
			(layer "F.Fab")
		)
		(fp_line
			(start 0.67945 0.3048)
			(end 0.120396 0.3048)
			(stroke
				(width 0.1)
				(type default)
			)
			(layer "F.Fab")
		)
		(fp_line
			(start -0.12065 0.2794)
			(end -0.12065 0.3048)
			(stroke
				(width 0.1)
				(type default)
			)
			(layer "F.Fab")
		)
		(fp_line
			(start 0.120396 0.2794)
			(end -0.12065 0.2794)
			(stroke
				(width 0.1)
				(type default)
			)
			(layer "F.Fab")
		)
		(fp_line
			(start -0.12065 -0.2794)
			(end 0.12065 -0.2794)
			(stroke
				(width 0.1)
				(type default)
			)
			(layer "F.Fab")
		)
		(fp_line
			(start 0.12065 -0.2794)
			(end 0.12065 -0.3048)
			(stroke
				(width 0.1)
				(type default)
			)
			(layer "F.Fab")
		)
		(fp_line
			(start 0.12065 -0.3048)
			(end 0.67945 -0.3048)
			(stroke
				(width 0.1)
				(type default)
			)
			(layer "F.Fab")
		)
		(fp_line
			(start 0.67945 -0.3048)
			(end 0.67945 0.3048)
			(stroke
				(width 0.1)
				(type default)
			)
			(layer "F.Fab")
		)
		(fp_line
			(start -0.67945 -0.305054)
			(end -0.12065 -0.305054)
			(stroke
				(width 0.1)
				(type default)
			)
			(layer "F.Fab")
		)
		(fp_line
			(start -0.12065 -0.305054)
			(end -0.12065 -0.2794)
			(stroke
				(width 0.1)
				(type default)
			)
			(layer "F.Fab")
		)
		(pad "1" smd circle
			(at -0.40005 0 270)
			(size 0 0)
			(layers "F.Cu" "F.Mask" "F.Paste")
			(net "CPU0_XTRIG_R2_L6")
		)
		(pad "2" smd circle
			(at 0.40005 0 270)
			(size 0 0)
			(layers "F.Cu" "F.Mask" "F.Paste")
			(net "CPU0_XTRIG_L6")
		)
	)
)
